# S9S_MB_2U (Grand Teton) — schematic netlist excerpt (pin names and nets, part order shuffled) for the footprints in the layout excerpt that follows; sources: Cadence DE-HDL packaged netlist, KiCad conversion of 03242023_DA0F0TMBIJ0_F0T_Motherboard_J_brd_V01_OCP.brd

R908  Q_RES  33.2 1% CHIP  pkg 0402LF  page 114 : A = PWRGD_CHH_CPU1_DIMM2 ; B = PWRGD_FAIL_CPU1_GH

U222  74CBTLV3126PW  IC  pkg TSSOP14  page 160
  \1oe\  = FB_BMC_ISOLATE1
  \1a\  = NCSI_BMC_RXD1_R1
  \1b\  = NCSI_OCP_V3_2_RXD1
  \2oe\  = FB_BMC_ISOLATE1
  \2a\  = NCSI_BMC_RXD0_R1
  \2b\  = NCSI_OCP_V3_2_RXD0
  GND  = GND
  \3b\  = NCSI_OCP_V3_2_CRS_DV
  \3a\  = NCSI_BMC_CRS_DV_R1
  \3oe\  = FB_BMC_ISOLATE1
  \4b\  = OCP_V3_2_ISO1_RBT_ARB_IN
  \4a\  = OCP_V3_2_RBT_ARB_IN_R
  \4oe\  = FB_BMC_ISOLATE1
  VCC  = P3V3_AUX

(kicad_pcb
	(version 20260206)
	(generator "pcbnew")
	(generator_version "10.0")
	(general
		(thickness 1.6)
		(legacy_teardrops no)
	)
	(paper "A4")
	(title_block
		(title "03242023_DA0F0TMBIJ0_F0T_Motherboard_J_brd_V01_OCP.brd")
		(comment 1 "Grand Teton / footprints 4493-4494 of 6105")
	)
	(layers
		(0 "F.Cu" signal "TOP")
		(4 "In1.Cu" signal "GND")
		(6 "In2.Cu" signal "IN1")
		(8 "In3.Cu" signal "GND1")
		(10 "In4.Cu" signal "IN2")
		(12 "In5.Cu" signal "GND2")
		(14 "In6.Cu" signal "IN3")
		(16 "In7.Cu" signal "GND3")
		(18 "In8.Cu" signal "VCC")
		(20 "In9.Cu" signal "VCC1")
		(22 "In10.Cu" signal "GND4")
		(24 "In11.Cu" signal "IN4")
		(26 "In12.Cu" signal "GND5")
		(28 "In13.Cu" signal "IN5")
		(30 "In14.Cu" signal "GND6")
		(32 "In15.Cu" signal "IN6")
		(34 "In16.Cu" signal "GND7")
		(2 "B.Cu" signal "BOTTOM")
		(9 "F.Adhes" user "F.Adhesive")
		(11 "B.Adhes" user "B.Adhesive")
		(13 "F.Paste" user "Package Geometry/Pastemask Top")
		(15 "B.Paste" user "Package Geometry/Pastemask Bottom")
		(5 "F.SilkS" user "Ref Des/Silkscreen Top")
		(7 "B.SilkS" user "Ref Des/Silkscreen Bottom")
		(1 "F.Mask" user "Board Geometry/Soldermask Top")
		(3 "B.Mask" user "Board Geometry/Soldermask Bottom")
		(17 "Dwgs.User" user "User.Drawings")
		(19 "Cmts.User" user "User.Comments")
		(21 "Eco1.User" user "User.Eco1")
		(23 "Eco2.User" user "User.Eco2")
		(25 "Edge.Cuts" user "Board Geometry/Outline")
		(27 "Margin" user)
		(31 "F.CrtYd" user "Package Geometry/Place Bound Top")
		(29 "B.CrtYd" user "Package Geometry/Place Bound Bottom")
		(35 "F.Fab" user "Ref Des/Assembly Top")
		(33 "B.Fab" user "Ref Des/Assembly Bottom")
	)
	(footprint ""
		(layer "B.Cu")
		(at 208.127854 -318.641476 90)
		(property "Reference" "R908"
			(at 0 0 90)
			(layer "B.SilkS")
			(hide yes)
			(effects
				(font
					(size 1.27 1.27)
				)
				(justify mirror)
			)
		)
		(property "Value" ""
			(at 0 0 90)
			(layer "B.Fab")
			(effects
				(font
					(size 1.27 1.27)
				)
				(justify mirror)
			)
		)
		(duplicate_pad_numbers_are_jumpers no)
		(fp_line
			(start 0.7874 -0.4064)
			(end -0.7874 -0.4064)
			(stroke
				(width 0.1524)
				(type default)
			)
			(layer "B.SilkS")
		)
		(fp_line
			(start -0.7874 -0.4064)
			(end -0.7874 0.4064)
			(stroke
				(width 0.1524)
				(type default)
			)
			(layer "B.SilkS")
		)
		(fp_line
			(start 0.7874 0.4064)
			(end 0.7874 -0.4064)
			(stroke
				(width 0.1524)
				(type default)
			)
			(layer "B.SilkS")
		)
		(fp_line
			(start -0.7874 0.4064)
			(end 0.7874 0.4064)
			(stroke
				(width 0.1524)
				(type default)
			)
			(layer "B.SilkS")
		)
		(fp_line
			(start 0.67945 -0.305054)
			(end 0.12065 -0.305054)
			(stroke
				(width 0.1)
				(type default)
			)
			(layer "B.Fab")
		)
		(fp_line
			(start 0.12065 -0.305054)
			(end 0.12065 -0.2794)
			(stroke
				(width 0.1)
				(type default)
			)
			(layer "B.Fab")
		)
		(fp_line
			(start -0.12065 -0.3048)
			(end -0.67945 -0.3048)
			(stroke
				(width 0.1)
				(type default)
			)
			(layer "B.Fab")
		)
		(fp_line
			(start -0.67945 -0.3048)
			(end -0.67945 0.3048)
			(stroke
				(width 0.1)
				(type default)
			)
			(layer "B.Fab")
		)
		(fp_line
			(start 0.12065 -0.2794)
			(end -0.12065 -0.2794)
			(stroke
				(width 0.1)
				(type default)
			)
			(layer "B.Fab")
		)
		(fp_line
			(start -0.12065 -0.2794)
			(end -0.12065 -0.3048)
			(stroke
				(width 0.1)
				(type default)
			)
			(layer "B.Fab")
		)
		(fp_line
			(start 0.12065 0.2794)
			(end 0.12065 0.3048)
			(stroke
				(width 0.1)
				(type default)
			)
			(layer "B.Fab")
		)
		(fp_line
			(start -0.120396 0.2794)
			(end 0.12065 0.2794)
			(stroke
				(width 0.1)
				(type default)
			)
			(layer "B.Fab")
		)
		(fp_line
			(start 0.67945 0.3048)
			(end 0.67945 -0.305054)
			(stroke
				(width 0.1)
				(type default)
			)
			(layer "B.Fab")
		)
		(fp_line
			(start 0.12065 0.3048)
			(end 0.67945 0.3048)
			(stroke
				(width 0.1)
				(type default)
			)
			(layer "B.Fab")
		)
		(fp_line
			(start -0.120396 0.3048)
			(end -0.120396 0.2794)
			(stroke
				(width 0.1)
				(type default)
			)
			(layer "B.Fab")
		)
		(fp_line
			(start -0.67945 0.3048)
			(end -0.120396 0.3048)
			(stroke
				(width 0.1)
				(type default)
			)
			(layer "B.Fab")
		)
		(pad "1" smd circle
			(at 0.40005 0 270)
			(size 0 0)
			(layers "B.Cu" "B.Mask" "B.Paste")
			(net "PWRGD_CHH_CPU1_DIMM2")
		)
		(pad "2" smd circle
			(at -0.40005 0 270)
			(size 0 0)
			(layers "B.Cu" "B.Mask" "B.Paste")
			(net "PWRGD_FAIL_CPU1_GH")
		)
	)
	(footprint ""
		(layer "B.Cu")
		(at 209.295746 -77.263752)
		(property "Reference" "U222"
			(at 2.032 -3.27533 0)
			(unlocked yes)
			(layer "B.SilkS")
			(effects
				(font
					(size 0.7874 0.5842)
					(thickness 0.1524)
				)
				(justify left mirror)
			)
		)
		(property "Value" ""
			(at 0 0 0)
			(layer "B.Fab")
			(effects
				(font
					(size 1.27 1.27)
				)
				(justify mirror)
			)
		)
		(duplicate_pad_numbers_are_jumpers no)
		(fp_line
			(start -2.0066 -2.5527)
			(end -2.0066 2.5527)
			(stroke
				(width 0.1524)
				(type default)
			)
			(layer "B.SilkS")
		)
		(fp_line
			(start -2.0066 2.5527)
			(end 2.0066 2.5527)
			(stroke
				(width 0.1524)
				(type default)
			)
			(layer "B.SilkS")
		)
		(fp_line
			(start -0.5715 -2.5527)
			(end -2.0066 -2.5527)
			(stroke
				(width 0.1524)
				(type default)
			)
			(layer "B.SilkS")
		)
		(fp_line
			(start 0 -1.9812)
			(end -0.5715 -2.5527)
			(stroke
				(width 0.1524)
				(type default)
			)
			(layer "B.SilkS")
		)
		(fp_line
			(start 0.5715 -2.5527)
			(end 0 -1.9812)
			(stroke
				(width 0.1524)
				(type default)
			)
			(layer "B.SilkS")
		)
		(fp_line
			(start 2.0066 -2.5527)
			(end 0.5715 -2.5527)
			(stroke
				(width 0.1524)
				(type default)
			)
			(layer "B.SilkS")
		)
		(fp_line
			(start 2.0066 2.5527)
			(end 2.0066 -2.5527)
			(stroke
				(width 0.1524)
				(type default)
			)
			(layer "B.SilkS")
		)
		(fp_poly
			(pts
				(xy 4.36372 -1.608328) (xy 3.81 -1.905) (xy 4.36372 -2.233168)
			)
			(stroke
				(width 0)
				(type default)
			)
			(fill yes)
			(layer "B.SilkS")
		)
		(fp_line
			(start -2.249932 -2.549906)
			(end -2.249932 2.549906)
			(stroke
				(width 0.1)
				(type default)
			)
			(layer "B.Fab")
		)
		(fp_line
			(start -2.249932 2.549906)
			(end 2.249932 2.549906)
			(stroke
				(width 0.1)
				(type default)
			)
			(layer "B.Fab")
		)
		(fp_line
			(start 2.249932 -2.549906)
			(end -2.249932 -2.549906)
			(stroke
				(width 0.1)
				(type default)
			)
			(layer "B.Fab")
		)
		(fp_line
			(start 2.249932 2.549906)
			(end 2.249932 -2.549906)
			(stroke
				(width 0.1)
				(type default)
			)
			(layer "B.Fab")
		)
		(fp_poly
			(pts
				(xy 4.36372 -1.608328) (xy 4.36372 -2.233168) (xy 3.81 -1.905)
			)
			(stroke
				(width 0)
				(type default)
			)
			(fill yes)
			(layer "B.Fab")
		)
		(pad "1" smd rect
			(at 2.921 -1.949958 270)
			(size 0.3556 1.4986)
			(layers "B.Cu" "B.Mask" "B.Paste")
			(net "FB_BMC_ISOLATE1")
		)
		(pad "2" smd rect
			(at 2.921 -1.299972 270)
			(size 0.3556 1.4986)
			(layers "B.Cu" "B.Mask" "B.Paste")
			(net "NCSI_BMC_RXD1_R1")
		)
		(pad "3" smd rect
			(at 2.921 -0.649986 270)
			(size 0.3556 1.4986)
			(layers "B.Cu" "B.Mask" "B.Paste")
			(net "NCSI_OCP_V3_2_RXD1")
		)
		(pad "4" smd rect
			(at 2.921 0 270)
			(size 0.3556 1.4986)
			(layers "B.Cu" "B.Mask" "B.Paste")
			(net "FB_BMC_ISOLATE1")
		)
		(pad "5" smd rect
			(at 2.921 0.649986 270)
			(size 0.3556 1.4986)
			(layers "B.Cu" "B.Mask" "B.Paste")
			(net "NCSI_BMC_RXD0_R1")
		)
		(pad "6" smd rect
			(at 2.921 1.299972 270)
			(size 0.3556 1.4986)
			(layers "B.Cu" "B.Mask" "B.Paste")
			(net "NCSI_OCP_V3_2_RXD0")
		)
		(pad "7" smd rect
			(at 2.921 1.949958 270)
			(size 0.3556 1.4986)
			(layers "B.Cu" "B.Mask" "B.Paste")
			(net "GND")
		)
		(pad "8" smd rect
			(at -2.921 1.949958 270)
			(size 0.3556 1.4986)
			(layers "B.Cu" "B.Mask" "B.Paste")
			(net "NCSI_OCP_V3_2_CRS_DV")
		)
		(pad "9" smd rect
			(at -2.921 1.299972 270)
			(size 0.3556 1.4986)
			(layers "B.Cu" "B.Mask" "B.Paste")
			(net "NCSI_BMC_CRS_DV_R1")
		)
		(pad "10" smd rect
			(at -2.921 0.649986 270)
			(size 0.3556 1.4986)
			(layers "B.Cu" "B.Mask" "B.Paste")
			(net "FB_BMC_ISOLATE1")
		)
		(pad "11" smd rect
			(at -2.921 0 270)
			(size 0.3556 1.4986)
			(layers "B.Cu" "B.Mask" "B.Paste")
			(net "OCP_V3_2_ISO1_RBT_ARB_IN")
		)
		(pad "12" smd rect
			(at -2.921 -0.649986 270)
			(size 0.3556 1.4986)
			(layers "B.Cu" "B.Mask" "B.Paste")
			(net "OCP_V3_2_RBT_ARB_IN_R")
		)
		(pad "13" smd rect
			(at -2.921 -1.299972 270)
			(size 0.3556 1.4986)
			(layers "B.Cu" "B.Mask" "B.Paste")
			(net "FB_BMC_ISOLATE1")
		)
		(pad "14" smd rect
			(at -2.921 -1.949958 270)
			(size 0.3556 1.4986)
			(layers "B.Cu" "B.Mask" "B.Paste")
			(net "P3V3_AUX")
		)
	)
)
